# T6G (Grand Teton) — schematic netlist excerpt (pin names and nets, part order shuffled) for the footprints in the layout excerpt that follows; sources: Cadence DE-HDL packaged netlist, KiCad conversion of 04192023_DAF0TMB3IC0_F0TG_MB_C_brd_V02_OCP.brd

C36  Q_CAP  0.1UF 25V 10% X7R  pkg 0402  page 133 : A = P3V3_AUX ; B = GND
PC317_7  Q_CAP  0.1UF 25V 10% X7R  pkg 0402  page 215 : A = PVDDCR_CPU0_P1_VCCS ; B = GND

(kicad_pcb
	(version 20260206)
	(generator "pcbnew")
	(generator_version "10.0")
	(general
		(thickness 1.6)
		(legacy_teardrops no)
	)
	(paper "A4")
	(title_block
		(title "04192023_DAF0TMB3IC0_F0TG_MB_C_brd_V02_OCP.brd")
		(comment 1 "Grand Teton / footprints 2663-2664 of 8354")
	)
	(layers
		(0 "F.Cu" signal "TOP")
		(4 "In1.Cu" signal "GND")
		(6 "In2.Cu" signal "IN1")
		(8 "In3.Cu" signal "GND1")
		(10 "In4.Cu" signal "IN2")
		(12 "In5.Cu" signal "GND2")
		(14 "In6.Cu" signal "IN3")
		(16 "In7.Cu" signal "GND3")
		(18 "In8.Cu" signal "VCC")
		(20 "In9.Cu" signal "VCC1")
		(22 "In10.Cu" signal "GND4")
		(24 "In11.Cu" signal "IN4")
		(26 "In12.Cu" signal "GND5")
		(28 "In13.Cu" signal "IN5")
		(30 "In14.Cu" signal "GND6")
		(32 "In15.Cu" signal "IN6")
		(34 "In16.Cu" signal "GND7")
		(2 "B.Cu" signal "BOTTOM")
		(9 "F.Adhes" user "F.Adhesive")
		(11 "B.Adhes" user "B.Adhesive")
		(13 "F.Paste" user "Package Geometry/Pastemask Top")
		(15 "B.Paste" user "Package Geometry/Pastemask Bottom")
		(5 "F.SilkS" user "Ref Des/Silkscreen Top")
		(7 "B.SilkS" user "Ref Des/Silkscreen Bottom")
		(1 "F.Mask" user "Board Geometry/Soldermask Top")
		(3 "B.Mask" user "Board Geometry/Soldermask Bottom")
		(17 "Dwgs.User" user "User.Drawings")
		(19 "Cmts.User" user "User.Comments")
		(21 "Eco1.User" user "User.Eco1")
		(23 "Eco2.User" user "User.Eco2")
		(25 "Edge.Cuts" user "Board Geometry/Outline")
		(27 "Margin" user)
		(31 "F.CrtYd" user "Package Geometry/Place Bound Top")
		(29 "B.CrtYd" user "Package Geometry/Place Bound Bottom")
		(35 "F.Fab" user "Ref Des/Assembly Top")
		(33 "B.Fab" user "Ref Des/Assembly Bottom")
	)
	(footprint ""
		(layer "F.Cu")
		(at 461.41132 -38.565836)
		(property "Reference" "C36"
			(at 0 0 0)
			(layer "F.SilkS")
			(hide yes)
			(effects
				(font
					(size 1.27 1.27)
				)
			)
		)
		(property "Value" ""
			(at 0 0 0)
			(layer "F.Fab")
			(effects
				(font
					(size 1.27 1.27)
				)
			)
		)
		(duplicate_pad_numbers_are_jumpers no)
		(fp_line
			(start -0.7874 -0.4064)
			(end 0.7874 -0.4064)
			(stroke
				(width 0.1524)
				(type default)
			)
			(layer "F.SilkS")
		)
		(fp_line
			(start -0.7874 0.4064)
			(end -0.7874 -0.4064)
			(stroke
				(width 0.1524)
				(type default)
			)
			(layer "F.SilkS")
		)
		(fp_line
			(start 0.7874 -0.4064)
			(end 0.7874 0.4064)
			(stroke
				(width 0.1524)
				(type default)
			)
			(layer "F.SilkS")
		)
		(fp_line
			(start 0.7874 0.4064)
			(end -0.7874 0.4064)
			(stroke
				(width 0.1524)
				(type default)
			)
			(layer "F.SilkS")
		)
		(fp_line
			(start -0.67945 -0.305054)
			(end -0.12065 -0.305054)
			(stroke
				(width 0.1)
				(type default)
			)
			(layer "F.Fab")
		)
		(fp_line
			(start -0.67945 0.3048)
			(end -0.67945 -0.305054)
			(stroke
				(width 0.1)
				(type default)
			)
			(layer "F.Fab")
		)
		(fp_line
			(start -0.12065 -0.305054)
			(end -0.12065 -0.2794)
			(stroke
				(width 0.1)
				(type default)
			)
			(layer "F.Fab")
		)
		(fp_line
			(start -0.12065 -0.2794)
			(end 0.12065 -0.2794)
			(stroke
				(width 0.1)
				(type default)
			)
			(layer "F.Fab")
		)
		(fp_line
			(start -0.12065 0.2794)
			(end -0.12065 0.3048)
			(stroke
				(width 0.1)
				(type default)
			)
			(layer "F.Fab")
		)
		(fp_line
			(start -0.12065 0.3048)
			(end -0.67945 0.3048)
			(stroke
				(width 0.1)
				(type default)
			)
			(layer "F.Fab")
		)
		(fp_line
			(start 0.120396 0.2794)
			(end -0.12065 0.2794)
			(stroke
				(width 0.1)
				(type default)
			)
			(layer "F.Fab")
		)
		(fp_line
			(start 0.120396 0.3048)
			(end 0.120396 0.2794)
			(stroke
				(width 0.1)
				(type default)
			)
			(layer "F.Fab")
		)
		(fp_line
			(start 0.12065 -0.3048)
			(end 0.67945 -0.3048)
			(stroke
				(width 0.1)
				(type default)
			)
			(layer "F.Fab")
		)
		(fp_line
			(start 0.12065 -0.2794)
			(end 0.12065 -0.3048)
			(stroke
				(width 0.1)
				(type default)
			)
			(layer "F.Fab")
		)
		(fp_line
			(start 0.67945 -0.3048)
			(end 0.67945 0.3048)
			(stroke
				(width 0.1)
				(type default)
			)
			(layer "F.Fab")
		)
		(fp_line
			(start 0.67945 0.3048)
			(end 0.120396 0.3048)
			(stroke
				(width 0.1)
				(type default)
			)
			(layer "F.Fab")
		)
		(pad "1" smd circle
			(at -0.40005 0)
			(size 0 0)
			(layers "F.Cu" "F.Mask" "F.Paste")
			(net "P3V3_AUX")
		)
		(pad "2" smd circle
			(at 0.40005 0)
			(size 0 0)
			(layers "F.Cu" "F.Mask" "F.Paste")
			(net "GND")
		)
	)
	(footprint ""
		(layer "F.Cu")
		(at 118.379494 -167.06596 -90)
		(property "Reference" "PC317_7"
			(at 0 0 270)
			(layer "F.SilkS")
			(hide yes)
			(effects
				(font
					(size 1.27 1.27)
				)
			)
		)
		(property "Value" ""
			(at 0 0 270)
			(layer "F.Fab")
			(effects
				(font
					(size 1.27 1.27)
				)
			)
		)
		(duplicate_pad_numbers_are_jumpers no)
		(fp_line
			(start -0.7874 0.4064)
			(end -0.7874 -0.4064)
			(stroke
				(width 0.1524)
				(type default)
			)
			(layer "F.SilkS")
		)
		(fp_line
			(start 0.7874 0.4064)
			(end -0.7874 0.4064)
			(stroke
				(width 0.1524)
				(type default)
			)
			(layer "F.SilkS")
		)
		(fp_line
			(start -0.7874 -0.4064)
			(end 0.7874 -0.4064)
			(stroke
				(width 0.1524)
				(type default)
			)
			(layer "F.SilkS")
		)
		(fp_line
			(start 0.7874 -0.4064)
			(end 0.7874 0.4064)
			(stroke
				(width 0.1524)
				(type default)
			)
			(layer "F.SilkS")
		)
		(fp_line
			(start -0.67945 0.3048)
			(end -0.67945 -0.305054)
			(stroke
				(width 0.1)
				(type default)
			)
			(layer "F.Fab")
		)
		(fp_line
			(start -0.12065 0.3048)
			(end -0.67945 0.3048)
			(stroke
				(width 0.1)
				(type default)
			)
			(layer "F.Fab")
		)
		(fp_line
			(start 0.120396 0.3048)
			(end 0.120396 0.2794)
			(stroke
				(width 0.1)
				(type default)
			)
			(layer "F.Fab")
		)
		(fp_line
			(start 0.67945 0.3048)
			(end 0.120396 0.3048)
			(stroke
				(width 0.1)
				(type default)
			)
			(layer "F.Fab")
		)
		(fp_line
			(start -0.12065 0.2794)
			(end -0.12065 0.3048)
			(stroke
				(width 0.1)
				(type default)
			)
			(layer "F.Fab")
		)
		(fp_line
			(start 0.120396 0.2794)
			(end -0.12065 0.2794)
			(stroke
				(width 0.1)
				(type default)
			)
			(layer "F.Fab")
		)
		(fp_line
			(start -0.12065 -0.2794)
			(end 0.12065 -0.2794)
			(stroke
				(width 0.1)
				(type default)
			)
			(layer "F.Fab")
		)
		(fp_line
			(start 0.12065 -0.2794)
			(end 0.12065 -0.3048)
			(stroke
				(width 0.1)
				(type default)
			)
			(layer "F.Fab")
		)
		(fp_line
			(start 0.12065 -0.3048)
			(end 0.67945 -0.3048)
			(stroke
				(width 0.1)
				(type default)
			)
			(layer "F.Fab")
		)
		(fp_line
			(start 0.67945 -0.3048)
			(end 0.67945 0.3048)
			(stroke
				(width 0.1)
				(type default)
			)
			(layer "F.Fab")
		)
		(fp_line
			(start -0.67945 -0.305054)
			(end -0.12065 -0.305054)
			(stroke
				(width 0.1)
				(type default)
			)
			(layer "F.Fab")
		)
		(fp_line
			(start -0.12065 -0.305054)
			(end -0.12065 -0.2794)
			(stroke
				(width 0.1)
				(type default)
			)
			(layer "F.Fab")
		)
		(pad "1" smd circle
			(at -0.40005 0 270)
			(size 0 0)
			(layers "F.Cu" "F.Mask" "F.Paste")
			(net "PVDDCR_CPU0_P1_VCCS")
		)
		(pad "2" smd circle
			(at 0.40005 0 270)
			(size 0 0)
			(layers "F.Cu" "F.Mask" "F.Paste")
			(net "GND")
		)
	)
)
